(kicad_pcb
	(version 20241229)
	(generator "pcbnew")
	(generator_version "9.0")
	(general
		(thickness 1.711)
		(legacy_teardrops no)
	)
	(paper "A4")
	(title_block
		(title "Antmicro Baseboard for Jetson AGX Thor")
		(date "2026-02-18")
		(rev "1.1.0")
		(company "Antmicro Ltd")
		(comment 1 "www.antmicro.com")
		(comment 9 "footprints 524-526 of 1170")
	)
	(layers
		(0 "F.Cu" signal)
		(4 "In1.Cu" signal)
		(6 "In2.Cu" signal)
		(8 "In3.Cu" signal)
		(10 "In4.Cu" jumper)
		(12 "In5.Cu" signal)
		(14 "In6.Cu" signal)
		(16 "In7.Cu" signal)
		(18 "In8.Cu" signal)
		(2 "B.Cu" signal)
		(9 "F.Adhes" user "F.Adhesive")
		(11 "B.Adhes" user "B.Adhesive")
		(13 "F.Paste" user)
		(15 "B.Paste" user)
		(5 "F.SilkS" user "F.Silkscreen")
		(7 "B.SilkS" user "B.Silkscreen")
		(1 "F.Mask" user)
		(3 "B.Mask" user)
		(17 "Dwgs.User" user "User.Drawings")
		(19 "Cmts.User" user "User.Comments")
		(21 "Eco1.User" user "User.Eco1")
		(23 "Eco2.User" user "User.Eco2")
		(25 "Edge.Cuts" user)
		(27 "Margin" user)
		(31 "F.CrtYd" user "F.Courtyard")
		(29 "B.CrtYd" user "B.Courtyard")
		(35 "F.Fab" user)
		(33 "B.Fab" user)
	)
	(footprint "antmicro-footprints:USB-C_Receptacle_Kycon_KUSBX-SL2-CS1N24-B-TR"
		(locked yes)
		(layer "F.Cu")
		(at 236.455532 128.21 90)
		(descr "USB-C (USB TYPE-C) USB 3.2 Gen 2 (USB 3.1 Gen 2, Superspeed + (USB 3.1)) Receptacle Connector 24 Position Through Hole, Right Angle")
		(tags "CONNECTOR, USB")
		(property "Reference" "J5"
			(at 3.11 -10.885532 180)
			(layer "F.SilkS")
			(effects
				(font
					(size 0.7 0.7)
					(thickness 0.15)
				)
				(justify left bottom)
			)
		)
		(property "Value" "USB-C_Kycon_KUSBX-SL2-CS1N24-B-TR"
			(at 0 7.5 90)
			(layer "F.Fab")
			(effects
				(font
					(size 0.7 0.7)
					(thickness 0.15)
				)
				(justify right top)
			)
		)
		(property "Datasheet" "https://www.kycon.com/Pub_Eng_Draw/KUSBX-SL2-CS1N24-B-TR.pdf"
			(at 0 0 90)
			(layer "F.Fab")
			(hide yes)
			(effects
				(font
					(size 1.27 1.27)
					(thickness 0.15)
				)
			)
		)
		(property "Description" "USB-C (USB TYPE-C) USB 3.2 Gen 2 (USB 3.1 Gen 2, Superspeed + (USB 3.1)) USB PD Receptacle Connector 24 Position Surface Mount"
			(at 0 0 90)
			(layer "F.Fab")
			(hide yes)
			(effects
				(font
					(size 1.27 1.27)
					(thickness 0.15)
				)
			)
		)
		(property "MPN" "KUSBX-SL2-CS1N24-B-TR"
			(at 0 0 90)
			(unlocked yes)
			(layer "F.Fab")
			(hide yes)
			(effects
				(font
					(size 1 1)
					(thickness 0.15)
				)
			)
		)
		(property "Manufacturer" "Kycon"
			(at 0 0 90)
			(unlocked yes)
			(layer "F.Fab")
			(hide yes)
			(effects
				(font
					(size 1 1)
					(thickness 0.15)
				)
			)
		)
		(property "License" "Apache-2.0"
			(at 0 0 90)
			(unlocked yes)
			(layer "F.Fab")
			(hide yes)
			(effects
				(font
					(size 1 1)
					(thickness 0.15)
				)
			)
		)
		(property "Author" "Antmicro"
			(at 0 0 90)
			(unlocked yes)
			(layer "F.Fab")
			(hide yes)
			(effects
				(font
					(size 1 1)
					(thickness 0.15)
				)
			)
		)
		(sheetname "/USB Hub/")
		(sheetfile "usb_hub.kicad_sch")
		(attr smd)
		(fp_line
			(start 1 -8.8)
			(end 1 -8.8)
			(stroke
				(width 0.15)
				(type solid)
			)
			(layer "F.SilkS")
		)
		(fp_line
			(start 1 -8.8)
			(end -1 -8.8)
			(stroke
				(width 0.15)
				(type solid)
			)
			(layer "F.SilkS")
		)
		(fp_line
			(start -1 -8.8)
			(end 1 -8.8)
			(stroke
				(width 0.15)
				(type solid)
			)
			(layer "F.SilkS")
		)
		(fp_line
			(start -1 -8.8)
			(end -1 -8.8)
			(stroke
				(width 0.15)
				(type solid)
			)
			(layer "F.SilkS")
		)
		(fp_rect
			(start -4 -9.4)
			(end 4 5.65)
			(stroke
				(width 0.05)
				(type solid)
			)
			(fill no)
			(layer "F.CrtYd")
		)
		(fp_line
			(start 2.25 -8.8)
			(end -2.25 -8.8)
			(stroke
				(width 0.15)
				(type solid)
			)
			(layer "F.Fab")
		)
		(fp_line
			(start -2.25 -8.8)
			(end -2.25 5.5)
			(stroke
				(width 0.15)
				(type solid)
			)
			(layer "F.Fab")
		)
		(fp_line
			(start 2.25 5.5)
			(end 2.25 -8.8)
			(stroke
				(width 0.15)
				(type solid)
			)
			(layer "F.Fab")
		)
		(fp_line
			(start -2.25 5.5)
			(end 2.25 5.5)
			(stroke
				(width 0.15)
				(type solid)
			)
			(layer "F.Fab")
		)
		(fp_text user "License: Apache-2.0"
			(at -5.47 10.9 90)
			(layer "F.Fab")
			(effects
				(font
					(size 0.7 0.7)
					(thickness 0.15)
				)
				(justify left bottom)
			)
		)
		(fp_text user "Author: Antmicro"
			(at -5.47 9.7 90)
			(layer "F.Fab")
			(effects
				(font
					(size 0.7 0.7)
					(thickness 0.15)
				)
				(justify left bottom)
			)
		)
		(fp_text user "${REFERENCE}"
			(at -5.47 8.5 90)
			(layer "F.Fab")
			(effects
				(font
					(size 0.7 0.7)
					(thickness 0.15)
				)
				(justify left bottom)
			)
		)
		(pad "" np_thru_hole circle
			(at 0 -7.6 90)
			(size 1.1 1.1)
			(drill 1.1)
			(layers "*.Cu" "*.Mask")
		)
		(pad "" np_thru_hole circle
			(at 0 0 90)
			(size 1 1)
			(drill 1)
			(layers "*.Cu" "*.Mask")
		)
		(pad "A1" smd rect
			(at 1.1375 -6.525 180)
			(size 0.25 1.625)
			(layers "F.Cu" "F.Mask" "F.Paste")
			(net 1 "GND")
			(pinfunction "GND")
			(pintype "power_in")
		)
		(pad "A2" smd rect
			(at 1.1375 -6.025 180)
			(size 0.25 1.625)
			(layers "F.Cu" "F.Mask" "F.Paste")
			(net 78 "/USB Hub/USBC4_CONN_TX1_P")
			(pinfunction "TX_{1}+")
			(pintype "bidirectional")
		)
		(pad "A3" smd rect
			(at 1.1375 -5.525 180)
			(size 0.25 1.625)
			(layers "F.Cu" "F.Mask" "F.Paste")
			(net 91 "/USB Hub/USBC4_CONN_TX1_N")
			(pinfunction "TX_{1}-")
			(pintype "bidirectional")
		)
		(pad "A4" smd rect
			(at 1.1375 -5.025 180)
			(size 0.25 1.625)
			(layers "F.Cu" "F.Mask" "F.Paste")
			(net 115 "/USB Hub/USBC4_VBUS")
			(pinfunction "VBUS")
			(pintype "power_in")
		)
		(pad "A5" smd rect
			(at 1.1375 -4.525 180)
			(size 0.25 1.625)
			(layers "F.Cu" "F.Mask" "F.Paste")
			(net 503 "/USB Hub/USBC4_CC_{1}")
			(pinfunction "CC_{1}")
			(pintype "bidirectional")
		)
		(pad "A6" smd rect
			(at 1.1375 -4.025 180)
			(size 0.25 1.625)
			(layers "F.Cu" "F.Mask" "F.Paste")
			(net 505 "/USB Hub/USBC4_D+")
			(pinfunction "D_{A}+")
			(pintype "bidirectional")
		)
		(pad "A7" smd rect
			(at 1.1375 -3.525 180)
			(size 0.25 1.625)
			(layers "F.Cu" "F.Mask" "F.Paste")
			(net 499 "/USB Hub/USBC4_D-")
			(pinfunction "D_{A}-")
			(pintype "bidirectional")
		)
		(pad "A8" smd rect
			(at 1.1375 -3.025 180)
			(size 0.25 1.625)
			(layers "F.Cu" "F.Mask" "F.Paste")
			(net 175 "unconnected-(J5-SBU_{1}-PadA8)")
			(pinfunction "SBU_{1}")
			(pintype "bidirectional+no_connect")
		)
		(pad "A9" smd rect
			(at 1.1375 -2.525 180)
			(size 0.25 1.625)
			(layers "F.Cu" "F.Mask" "F.Paste")
			(net 115 "/USB Hub/USBC4_VBUS")
			(pinfunction "VBUS")
			(pintype "passive")
		)
		(pad "A10" smd rect
			(at 1.1375 -2.025 180)
			(size 0.25 1.625)
			(layers "F.Cu" "F.Mask" "F.Paste")
			(net 498 "/USB Hub/USBC4_RX_{2}+")
			(pinfunction "RX_{2}-")
			(pintype "bidirectional")
		)
		(pad "A11" smd rect
			(at 1.1375 -1.525 180)
			(size 0.25 1.625)
			(layers "F.Cu" "F.Mask" "F.Paste")
			(net 500 "/USB Hub/USBC4_RX_{2}-")
			(pinfunction "RX_{2}+")
			(pintype "bidirectional")
		)
		(pad "A12" smd rect
			(at 1.1375 -1.025 180)
			(size 0.25 1.625)
			(layers "F.Cu" "F.Mask" "F.Paste")
			(net 1 "GND")
			(pinfunction "GND")
			(pintype "passive")
		)
		(pad "B1" smd rect
			(at -1.1375 -1.025 180)
			(size 0.25 1.625)
			(layers "F.Cu" "F.Mask" "F.Paste")
			(net 1 "GND")
			(pinfunction "GND")
			(pintype "passive")
		)
		(pad "B2" smd rect
			(at -1.1375 -1.525 180)
			(size 0.25 1.625)
			(layers "F.Cu" "F.Mask" "F.Paste")
			(net 80 "/USB Hub/USBC4_CONN_TX2_P")
			(pinfunction "TX_{2}+")
			(pintype "bidirectional")
		)
		(pad "B3" smd rect
			(at -1.1375 -2.025 180)
			(size 0.25 1.625)
			(layers "F.Cu" "F.Mask" "F.Paste")
			(net 110 "/USB Hub/USBC4_CONN_TX2_N")
			(pinfunction "TX_{2}-")
			(pintype "bidirectional")
		)
		(pad "B4" smd rect
			(at -1.1375 -2.525 180)
			(size 0.25 1.625)
			(layers "F.Cu" "F.Mask" "F.Paste")
			(net 115 "/USB Hub/USBC4_VBUS")
			(pinfunction "VBUS")
			(pintype "passive")
		)
		(pad "B5" smd rect
			(at -1.1375 -3.025 180)
			(size 0.25 1.625)
			(layers "F.Cu" "F.Mask" "F.Paste")
			(net 502 "/USB Hub/USBC4_CC_{2}")
			(pinfunction "CC_{2}")
			(pintype "bidirectional")
		)
		(pad "B6" smd rect
			(at -1.1375 -3.525 180)
			(size 0.25 1.625)
			(layers "F.Cu" "F.Mask" "F.Paste")
			(net 505 "/USB Hub/USBC4_D+")
			(pinfunction "D_{B}+")
			(pintype "bidirectional")
		)
		(pad "B7" smd rect
			(at -1.1375 -4.025 180)
			(size 0.25 1.625)
			(layers "F.Cu" "F.Mask" "F.Paste")
			(net 499 "/USB Hub/USBC4_D-")
			(pinfunction "D_{B}-")
			(pintype "bidirectional")
		)
		(pad "B8" smd rect
			(at -1.1375 -4.525 180)
			(size 0.25 1.625)
			(layers "F.Cu" "F.Mask" "F.Paste")
			(net 177 "unconnected-(J5-SBU_{2}-PadB8)")
			(pinfunction "SBU_{2}")
			(pintype "bidirectional+no_connect")
		)
		(pad "B9" smd rect
			(at -1.1375 -5.025 180)
			(size 0.25 1.625)
			(layers "F.Cu" "F.Mask" "F.Paste")
			(net 115 "/USB Hub/USBC4_VBUS")
			(pinfunction "VBUS")
			(pintype "passive")
		)
		(pad "B10" smd rect
			(at -1.1375 -5.525 180)
			(size 0.25 1.625)
			(layers "F.Cu" "F.Mask" "F.Paste")
			(net 504 "/USB Hub/USBC4_RX_{1}+")
			(pinfunction "RX_{1}-")
			(pintype "bidirectional")
		)
		(pad "B11" smd rect
			(at -1.1375 -6.025 180)
			(size 0.25 1.625)
			(layers "F.Cu" "F.Mask" "F.Paste")
			(net 501 "/USB Hub/USBC4_RX_{1}-")
			(pinfunction "RX_{1}+")
			(pintype "bidirectional")
		)
		(pad "B12" smd rect
			(at -1.1375 -6.525 180)
			(size 0.25 1.625)
			(layers "F.Cu" "F.Mask" "F.Paste")
			(net 1 "GND")
			(pinfunction "GND")
			(pintype "passive")
		)
		(pad "SH" thru_hole oval
			(at -3 -7.849 90)
			(size 1 2.05)
			(drill oval 0.6 1.65)
			(layers "*.Cu" "*.Mask")
			(remove_unused_layers no)
			(net 1 "GND")
			(pinfunction "SH")
			(pintype "passive")
		)
		(pad "SH" thru_hole oval
			(at -3 0.25 90)
			(size 1 2.05)
			(drill oval 0.6 1.65)
			(layers "*.Cu" "*.Mask")
			(remove_unused_layers no)
			(net 1 "GND")
			(pinfunction "SH")
			(pintype "passive")
		)
		(pad "SH" thru_hole oval
			(at 3 -7.849 90)
			(size 1 2.05)
			(drill oval 0.6 1.65)
			(layers "*.Cu" "*.Mask")
			(remove_unused_layers no)
			(net 1 "GND")
			(pinfunction "SH")
			(pintype "passive")
		)
		(pad "SH" thru_hole oval
			(at 3 0.25 90)
			(size 1 2.05)
			(drill oval 0.6 1.65)
			(layers "*.Cu" "*.Mask")
			(remove_unused_layers no)
			(net 1 "GND")
			(pinfunction "SH")
			(pintype "passive")
		)
	)
	(footprint "antmicro-footprints:C_0402_1005Metric"
		(layer "F.Cu")
		(at 91.1 98.3)
		(descr "Capacitor SMD 0402")
		(tags "capacitor SMD 0402")
		(property "Reference" "C345"
			(at 1.1 0.500001 0)
			(layer "F.SilkS")
			(effects
				(font
					(size 0.7 0.7)
					(thickness 0.15)
				)
				(justify left bottom)
			)
		)
		(property "Value" "C_100n_0402"
			(at -1.022927 2.155213 0)
			(layer "F.Fab")
			(effects
				(font
					(size 0.7 0.7)
					(thickness 0.15)
				)
				(justify left bottom)
			)
		)
		(property "Datasheet" "https://www.murata.com/products/productdetail?partno=GRM155R61H104KE14%23"
			(at 0 0 0)
			(layer "F.Fab")
			(hide yes)
			(effects
				(font
					(size 1.27 1.27)
					(thickness 0.15)
				)
			)
		)
		(property "Description" "SMD Multilayer Ceramic Capacitor, 0.1 µF, 50 V, 0402 [1005 Metric], ± 10%, X5R, GRM Series"
			(at 0 0 0)
			(layer "F.Fab")
			(hide yes)
			(effects
				(font
					(size 1.27 1.27)
					(thickness 0.15)
				)
			)
		)
		(property "Manufacturer" "Murata"
			(at 0 0 0)
			(unlocked yes)
			(layer "F.Fab")
			(hide yes)
			(effects
				(font
					(size 1 1)
					(thickness 0.15)
				)
			)
		)
		(property "MPN" "GRM155R61H104KE14D"
			(at 0 0 0)
			(unlocked yes)
			(layer "F.Fab")
			(hide yes)
			(effects
				(font
					(size 1 1)
					(thickness 0.15)
				)
			)
		)
		(property "Val" "100n"
			(at 0 0 0)
			(unlocked yes)
			(layer "F.Fab")
			(hide yes)
			(effects
				(font
					(size 1 1)
					(thickness 0.15)
				)
			)
		)
		(property "License" "Apache-2.0"
			(at 0 0 0)
			(unlocked yes)
			(layer "F.Fab")
			(hide yes)
			(effects
				(font
					(size 1 1)
					(thickness 0.15)
				)
			)
		)
		(property "Author" "Antmicro"
			(at 0 0 0)
			(unlocked yes)
			(layer "F.Fab")
			(hide yes)
			(effects
				(font
					(size 1 1)
					(thickness 0.15)
				)
			)
		)
		(property "Voltage" "50V"
			(at 0 0 0)
			(unlocked yes)
			(layer "F.Fab")
			(hide yes)
			(effects
				(font
					(size 1 1)
					(thickness 0.15)
				)
			)
		)
		(property "Dielectric" "X5R"
			(at 0 0 0)
			(unlocked yes)
			(layer "F.Fab")
			(hide yes)
			(effects
				(font
					(size 1 1)
					(thickness 0.15)
				)
			)
		)
		(sheetname "/SoM_IO2/")
		(sheetfile "som_io2.kicad_sch")
		(attr smd)
		(fp_rect
			(start -0.925 -0.47)
			(end 0.925 0.47)
			(stroke
				(width 0.05)
				(type default)
			)
			(fill no)
			(layer "F.CrtYd")
		)
		(fp_line
			(start -0.494 -0.25)
			(end 0.504 -0.25)
			(stroke
				(width 0.15)
				(type solid)
			)
			(layer "F.Fab")
		)
		(fp_line
			(start -0.494 0.248)
			(end -0.494 -0.25)
			(stroke
				(width 0.15)
				(type solid)
			)
			(layer "F.Fab")
		)
		(fp_line
			(start 0.504 -0.25)
			(end 0.504 0.248)
			(stroke
				(width 0.15)
				(type solid)
			)
			(layer "F.Fab")
		)
		(fp_line
			(start 0.504 0.248)
			(end -0.494 0.248)
			(stroke
				(width 0.15)
				(type solid)
			)
			(layer "F.Fab")
		)
		(fp_text user "Author: Antmicro"
			(at -0.939 3.399 0)
			(layer "F.Fab")
			(effects
				(font
					(size 0.7 0.7)
					(thickness 0.15)
				)
				(justify left bottom)
			)
		)
		(fp_text user "${REFERENCE}"
			(at -0.939 4.599 0)
			(layer "F.Fab")
			(effects
				(font
					(size 0.7 0.7)
					(thickness 0.15)
				)
				(justify left bottom)
			)
		)
		(fp_text user "License: Apache-2.0"
			(at -0.939 5.799 0)
			(layer "F.Fab")
			(effects
				(font
					(size 0.7 0.7)
					(thickness 0.15)
				)
				(justify left bottom)
			)
		)
		(pad "1" smd roundrect
			(at -0.48 0)
			(size 0.59 0.64)
			(layers "F.Cu" "F.Mask" "F.Paste")
			(roundrect_rratio 0.25)
			(net 736 "/Expansion connector/DP3.TX1+")
			(pintype "passive")
		)
		(pad "2" smd roundrect
			(at 0.48 0)
			(size 0.59 0.64)
			(layers "F.Cu" "F.Mask" "F.Paste")
			(roundrect_rratio 0.25)
			(net 1265 "/SoM_IO2/DP3.TX1_C+")
			(pintype "passive")
		)
	)
	(footprint "antmicro-footprints:R_0402_1005Metric"
		(layer "F.Cu")
		(at 142.226999 108.15 -90)
		(descr "Resistor SMD 0402")
		(tags "resistor SMD 0402")
		(property "Reference" "R343"
			(at -1.45 -0.673001 90)
			(layer "F.SilkS")
			(effects
				(font
					(size 0.7 0.7)
					(thickness 0.15)
				)
				(justify right top)
			)
		)
		(property "Value" "R_10k_0402"
			(at -1.011843 1.772047 90)
			(layer "F.Fab")
			(effects
				(font
					(size 0.7 0.7)
					(thickness 0.15)
				)
				(justify right top)
			)
		)
		(property "Datasheet" "https://www.bourns.com/docs/product-datasheets/cr.pdf"
			(at 0 0 90)
			(layer "F.Fab")
			(hide yes)
			(effects
				(font
					(size 1.27 1.27)
					(thickness 0.15)
				)
			)
		)
		(property "Description" "SMD Chip Resistor, 10 kohm, ± 1%, 62.5 mW, 0402 [1005 Metric], Thick Film, General Purpose"
			(at 0 0 90)
			(layer "F.Fab")
			(hide yes)
			(effects
				(font
					(size 1.27 1.27)
					(thickness 0.15)
				)
			)
		)
		(property "Manufacturer" "Bourns"
			(at 0 0 270)
			(unlocked yes)
			(layer "F.Fab")
			(hide yes)
			(effects
				(font
					(size 1 1)
					(thickness 0.15)
				)
			)
		)
		(property "MPN" "CR0402-FX-1002GLF"
			(at 0 0 270)
			(unlocked yes)
			(layer "F.Fab")
			(hide yes)
			(effects
				(font
					(size 1 1)
					(thickness 0.15)
				)
			)
		)
		(property "Val" "10k"
			(at 0 0 270)
			(unlocked yes)
			(layer "F.Fab")
			(hide yes)
			(effects
				(font
					(size 1 1)
					(thickness 0.15)
				)
			)
		)
		(property "License" "Apache-2.0"
			(at 0 0 270)
			(unlocked yes)
			(layer "F.Fab")
			(hide yes)
			(effects
				(font
					(size 1 1)
					(thickness 0.15)
				)
			)
		)
		(property "Author" "Antmicro"
			(at 0 0 270)
			(unlocked yes)
			(layer "F.Fab")
			(hide yes)
			(effects
				(font
					(size 1 1)
					(thickness 0.15)
				)
			)
		)
		(property "Tolerance" "1%"
			(at 0 0 270)
			(unlocked yes)
			(layer "F.Fab")
			(hide yes)
			(effects
				(font
					(size 1 1)
					(thickness 0.15)
				)
			)
		)
		(sheetname "/Peripherals/")
		(sheetfile "peripherals.kicad_sch")
		(attr smd)
		(fp_rect
			(start -0.925 -0.47)
			(end 0.925 0.47)
			(stroke
				(width 0.05)
				(type default)
			)
			(fill no)
			(layer "F.CrtYd")
		)
		(fp_rect
			(start -0.5 -0.25)
			(end 0.5 0.25)
			(stroke
				(width 0.15)
				(type solid)
			)
			(fill no)
			(layer "F.Fab")
		)
		(fp_text user "${REFERENCE}"
			(at -0.95 3.168 90)
			(layer "F.Fab")
			(effects
				(font
					(size 0.7 0.7)
					(thickness 0.15)
				)
				(justify right top)
			)
		)
		(fp_text user "Author: Antmicro"
			(at -0.95 4.169 90)
			(layer "F.Fab")
			(effects
				(font
					(size 0.7 0.7)
					(thickness 0.15)
				)
				(justify right top)
			)
		)
		(fp_text user "License: Apache-2.0"
			(at -0.95 5.169 90)
			(layer "F.Fab")
			(effects
				(font
					(size 0.7 0.7)
					(thickness 0.15)
				)
				(justify right top)
			)
		)
		(pad "1" smd roundrect
			(at -0.48 0 270)
			(size 0.59 0.64)
			(layers "F.Cu" "F.Mask" "F.Paste")
			(roundrect_rratio 0.25)
			(net 1309 "/Peripherals/GPIO_EXP_IRQ")
			(pintype "passive")
		)
		(pad "2" smd roundrect
			(at 0.48 0 270)
			(size 0.59 0.64)
			(layers "F.Cu" "F.Mask" "F.Paste")
			(roundrect_rratio 0.25)
			(net 11 "+1V8")
			(pintype "passive")
		)
	)
)
